(kicad_pcb
	(version 20241229)
	(generator "pcbnew")
	(generator_version "9.0")
	(general
		(thickness 1.6642)
		(legacy_teardrops no)
	)
	(paper "A3")
	(title_block
		(title "PolarFire SoM")
		(date "2025-07-22")
		(rev "1.1.4")
		(company "Antmicro Ltd")
		(comment 1 "www.antmicro.com")
		(comment 9 "footprints 322-325 of 470")
	)
	(layers
		(0 "F.Cu" mixed)
		(4 "In1.Cu" power)
		(6 "In2.Cu" signal)
		(8 "In3.Cu" power)
		(10 "In4.Cu" signal)
		(12 "In5.Cu" power)
		(14 "In6.Cu" power)
		(16 "In7.Cu" signal)
		(18 "In8.Cu" power)
		(20 "In9.Cu" signal)
		(22 "In10.Cu" power)
		(24 "In11.Cu" signal)
		(26 "In12.Cu" signal)
		(2 "B.Cu" mixed)
		(9 "F.Adhes" user "F.Adhesive")
		(11 "B.Adhes" user "B.Adhesive")
		(13 "F.Paste" user)
		(15 "B.Paste" user)
		(5 "F.SilkS" user "F.Silkscreen")
		(7 "B.SilkS" user "B.Silkscreen")
		(1 "F.Mask" user)
		(3 "B.Mask" user)
		(17 "Dwgs.User" user "User.Drawings")
		(19 "Cmts.User" user "User.Comments")
		(21 "Eco1.User" user "User.Eco1")
		(23 "Eco2.User" user "User.Eco2")
		(25 "Edge.Cuts" user)
		(27 "Margin" user)
		(31 "F.CrtYd" user "F.Courtyard")
		(29 "B.CrtYd" user "B.Courtyard")
		(35 "F.Fab" user)
		(33 "B.Fab" user)
	)
	(footprint "antmicro-footprints:C_0402_1005Metric"
		(layer "B.Cu")
		(at 191.71 137.46 -90)
		(descr "Capacitor SMD 0402")
		(tags "capacitor SMD 0402")
		(property "Reference" "C56"
			(at -1.316 0.702 90)
			(layer "B.SilkS")
			(effects
				(font
					(size 0.7 0.7)
					(thickness 0.15)
				)
				(justify left bottom mirror)
			)
		)
		(property "Value" "C_4n7_0402"
			(at -1.022927 -2.155213 90)
			(layer "B.Fab")
			(hide yes)
			(effects
				(font
					(size 0.7 0.7)
					(thickness 0.15)
				)
				(justify left bottom mirror)
			)
		)
		(property "Datasheet" "https://product.tdk.com/en/search/capacitor/ceramic/mlcc/info?part_no=CGA2B3X7S2A472K050BB"
			(at 0 0 270)
			(layer "F.Fab")
			(hide yes)
			(effects
				(font
					(size 1.27 1.27)
					(thickness 0.15)
				)
			)
		)
		(property "Description" "SMD Multilayer Ceramic Capacitor, 4700 pF, 100 V, 0402 [1005 Metric], ± 10%, X7S, CGA"
			(at 0 0 270)
			(layer "F.Fab")
			(hide yes)
			(effects
				(font
					(size 1.27 1.27)
					(thickness 0.15)
				)
			)
		)
		(property "Author" "Antmicro"
			(at 54.25 329.17 0)
			(layer "B.Fab")
			(hide yes)
			(effects
				(font
					(size 1 1)
					(thickness 0.15)
				)
				(justify mirror)
			)
		)
		(property "Dielectric" "X7R"
			(at 54.25 329.17 0)
			(layer "B.Fab")
			(hide yes)
			(effects
				(font
					(size 1 1)
					(thickness 0.15)
				)
				(justify mirror)
			)
		)
		(property "License" "Apache-2.0"
			(at 54.25 329.17 0)
			(layer "B.Fab")
			(hide yes)
			(effects
				(font
					(size 1 1)
					(thickness 0.15)
				)
				(justify mirror)
			)
		)
		(property "MPN" "CGA2B3X7S2A472K050BB"
			(at 54.25 329.17 0)
			(layer "B.Fab")
			(hide yes)
			(effects
				(font
					(size 1 1)
					(thickness 0.15)
				)
				(justify mirror)
			)
		)
		(property "Manufacturer" "TDK"
			(at 54.25 329.17 0)
			(layer "B.Fab")
			(hide yes)
			(effects
				(font
					(size 1 1)
					(thickness 0.15)
				)
				(justify mirror)
			)
		)
		(property "Public" ""
			(at 54.25 329.17 0)
			(layer "B.Fab")
			(hide yes)
			(effects
				(font
					(size 1 1)
					(thickness 0.15)
				)
				(justify mirror)
			)
		)
		(property "Val" "4n7"
			(at 54.25 329.17 0)
			(layer "B.Fab")
			(hide yes)
			(effects
				(font
					(size 1 1)
					(thickness 0.15)
				)
				(justify mirror)
			)
		)
		(property "Voltage" "25V"
			(at 54.25 329.17 0)
			(layer "B.Fab")
			(hide yes)
			(effects
				(font
					(size 1 1)
					(thickness 0.15)
				)
				(justify mirror)
			)
		)
		(sheetname "/FPGA Supply/")
		(sheetfile "fpga-supply.kicad_sch")
		(attr smd)
		(fp_rect
			(start -0.925 0.47)
			(end 0.925 -0.47)
			(stroke
				(width 0.05)
				(type default)
			)
			(fill no)
			(layer "B.CrtYd")
		)
		(fp_line
			(start -0.494 0.25)
			(end 0.504 0.25)
			(stroke
				(width 0.15)
				(type solid)
			)
			(layer "B.Fab")
		)
		(fp_line
			(start 0.504 0.25)
			(end 0.504 -0.248)
			(stroke
				(width 0.15)
				(type solid)
			)
			(layer "B.Fab")
		)
		(fp_line
			(start -0.494 -0.248)
			(end -0.494 0.25)
			(stroke
				(width 0.15)
				(type solid)
			)
			(layer "B.Fab")
		)
		(fp_line
			(start 0.504 -0.248)
			(end -0.494 -0.248)
			(stroke
				(width 0.15)
				(type solid)
			)
			(layer "B.Fab")
		)
		(fp_text user "Author: Antmicro"
			(at -0.939 -3.399 90)
			(layer "B.Fab")
			(effects
				(font
					(size 0.7 0.7)
					(thickness 0.15)
				)
				(justify left bottom mirror)
			)
		)
		(fp_text user "${REFERENCE}"
			(at -0.939 -4.599 90)
			(layer "B.Fab")
			(effects
				(font
					(size 0.7 0.7)
					(thickness 0.15)
				)
				(justify left bottom mirror)
			)
		)
		(fp_text user "License: Apache-2.0"
			(at -0.939 -5.799 90)
			(layer "B.Fab")
			(effects
				(font
					(size 0.7 0.7)
					(thickness 0.15)
				)
				(justify left bottom mirror)
			)
		)
		(pad "1" smd roundrect
			(at -0.48 0 270)
			(size 0.59 0.64)
			(layers "B.Cu" "B.Mask" "B.Paste")
			(roundrect_rratio 0.25)
			(net 417 "GND")
			(pintype "passive")
		)
		(pad "2" smd roundrect
			(at 0.48 0 270)
			(size 0.59 0.64)
			(layers "B.Cu" "B.Mask" "B.Paste")
			(roundrect_rratio 0.25)
			(net 48 "+1V8")
			(pintype "passive")
		)
	)
	(footprint "antmicro-footprints:C_0402_1005Metric"
		(layer "B.Cu")
		(at 220.9575 147.295 90)
		(descr "Capacitor SMD 0402")
		(tags "capacitor SMD 0402")
		(property "Reference" "C227"
			(at -3.735 0.9525 90)
			(layer "B.SilkS")
			(effects
				(font
					(size 0.7 0.7)
					(thickness 0.15)
				)
				(justify right bottom mirror)
			)
		)
		(property "Value" "C_100n_0402"
			(at -1.022927 -2.155213 90)
			(layer "B.Fab")
			(hide yes)
			(effects
				(font
					(size 0.7 0.7)
					(thickness 0.15)
				)
				(justify right bottom mirror)
			)
		)
		(property "Datasheet" "https://www.murata.com/products/productdetail?partno=GRM155R61H104KE14%23"
			(at 0 0 90)
			(layer "F.Fab")
			(hide yes)
			(effects
				(font
					(size 1.27 1.27)
					(thickness 0.15)
				)
			)
		)
		(property "Description" "SMD Multilayer Ceramic Capacitor, 0.1 µF, 50 V, 0402 [1005 Metric], ± 10%, X5R, GRM Series"
			(at 0 0 90)
			(layer "F.Fab")
			(hide yes)
			(effects
				(font
					(size 1.27 1.27)
					(thickness 0.15)
				)
			)
		)
		(property "Author" "Antmicro"
			(at 368.2525 -73.6625 0)
			(layer "B.Fab")
			(hide yes)
			(effects
				(font
					(size 1 1)
					(thickness 0.15)
				)
				(justify mirror)
			)
		)
		(property "Dielectric" "X5R"
			(at 368.2525 -73.6625 0)
			(layer "B.Fab")
			(hide yes)
			(effects
				(font
					(size 1 1)
					(thickness 0.15)
				)
				(justify mirror)
			)
		)
		(property "License" "Apache-2.0"
			(at 368.2525 -73.6625 0)
			(layer "B.Fab")
			(hide yes)
			(effects
				(font
					(size 1 1)
					(thickness 0.15)
				)
				(justify mirror)
			)
		)
		(property "MPN" "GRM155R61H104KE14D"
			(at 368.2525 -73.6625 0)
			(layer "B.Fab")
			(hide yes)
			(effects
				(font
					(size 1 1)
					(thickness 0.15)
				)
				(justify mirror)
			)
		)
		(property "Manufacturer" "Murata"
			(at 368.2525 -73.6625 0)
			(layer "B.Fab")
			(hide yes)
			(effects
				(font
					(size 1 1)
					(thickness 0.15)
				)
				(justify mirror)
			)
		)
		(property "Public" ""
			(at 368.2525 -73.6625 0)
			(layer "B.Fab")
			(hide yes)
			(effects
				(font
					(size 1 1)
					(thickness 0.15)
				)
				(justify mirror)
			)
		)
		(property "Val" "100n"
			(at 368.2525 -73.6625 0)
			(layer "B.Fab")
			(hide yes)
			(effects
				(font
					(size 1 1)
					(thickness 0.15)
				)
				(justify mirror)
			)
		)
		(property "Voltage" "50V"
			(at 368.2525 -73.6625 0)
			(layer "B.Fab")
			(hide yes)
			(effects
				(font
					(size 1 1)
					(thickness 0.15)
				)
				(justify mirror)
			)
		)
		(sheetname "/WiFi_Bluetooth/")
		(sheetfile "wifi_bt.kicad_sch")
		(attr smd)
		(fp_rect
			(start -0.925 0.47)
			(end 0.925 -0.47)
			(stroke
				(width 0.05)
				(type default)
			)
			(fill no)
			(layer "B.CrtYd")
		)
		(fp_line
			(start 0.504 -0.248)
			(end -0.494 -0.248)
			(stroke
				(width 0.15)
				(type solid)
			)
			(layer "B.Fab")
		)
		(fp_line
			(start -0.494 -0.248)
			(end -0.494 0.25)
			(stroke
				(width 0.15)
				(type solid)
			)
			(layer "B.Fab")
		)
		(fp_line
			(start 0.504 0.25)
			(end 0.504 -0.248)
			(stroke
				(width 0.15)
				(type solid)
			)
			(layer "B.Fab")
		)
		(fp_line
			(start -0.494 0.25)
			(end 0.504 0.25)
			(stroke
				(width 0.15)
				(type solid)
			)
			(layer "B.Fab")
		)
		(fp_text user "License: Apache-2.0"
			(at -0.939 -5.799 270)
			(layer "B.Fab")
			(effects
				(font
					(size 0.7 0.7)
					(thickness 0.15)
				)
				(justify left bottom mirror)
			)
		)
		(fp_text user "${REFERENCE}"
			(at -0.939 -4.599 270)
			(layer "B.Fab")
			(effects
				(font
					(size 0.7 0.7)
					(thickness 0.15)
				)
				(justify left bottom mirror)
			)
		)
		(fp_text user "Author: Antmicro"
			(at -0.939 -3.399 270)
			(layer "B.Fab")
			(effects
				(font
					(size 0.7 0.7)
					(thickness 0.15)
				)
				(justify left bottom mirror)
			)
		)
		(pad "1" smd roundrect
			(at -0.48 0 90)
			(size 0.59 0.64)
			(layers "B.Cu" "B.Mask" "B.Paste")
			(roundrect_rratio 0.25)
			(net 417 "GND")
			(pintype "passive")
		)
		(pad "2" smd roundrect
			(at 0.48 0 90)
			(size 0.59 0.64)
			(layers "B.Cu" "B.Mask" "B.Paste")
			(roundrect_rratio 0.25)
			(net 172 "BT_REG_ON")
			(pintype "passive")
		)
	)
	(footprint "antmicro-footprints:C_0402_1005Metric"
		(layer "B.Cu")
		(at 198.1 140.564 90)
		(descr "Capacitor SMD 0402")
		(tags "capacitor SMD 0402")
		(property "Reference" "C24"
			(at 1.114 -1.99 270)
			(layer "B.SilkS")
			(effects
				(font
					(size 0.7 0.7)
					(thickness 0.15)
				)
				(justify left bottom mirror)
			)
		)
		(property "Value" "C_4n7_0402"
			(at -1.022927 -2.155213 270)
			(layer "B.Fab")
			(hide yes)
			(effects
				(font
					(size 0.7 0.7)
					(thickness 0.15)
				)
				(justify left bottom mirror)
			)
		)
		(property "Datasheet" "https://product.tdk.com/en/search/capacitor/ceramic/mlcc/info?part_no=CGA2B3X7S2A472K050BB"
			(at 0 0 90)
			(layer "F.Fab")
			(hide yes)
			(effects
				(font
					(size 1.27 1.27)
					(thickness 0.15)
				)
			)
		)
		(property "Description" "SMD Multilayer Ceramic Capacitor, 4700 pF, 100 V, 0402 [1005 Metric], ± 10%, X7S, CGA"
			(at 0 0 90)
			(layer "F.Fab")
			(hide yes)
			(effects
				(font
					(size 1.27 1.27)
					(thickness 0.15)
				)
			)
		)
		(property "Author" "Antmicro"
			(at 338.664 -57.536 0)
			(layer "B.Fab")
			(hide yes)
			(effects
				(font
					(size 1 1)
					(thickness 0.15)
				)
				(justify mirror)
			)
		)
		(property "Dielectric" "X7R"
			(at 338.664 -57.536 0)
			(layer "B.Fab")
			(hide yes)
			(effects
				(font
					(size 1 1)
					(thickness 0.15)
				)
				(justify mirror)
			)
		)
		(property "License" "Apache-2.0"
			(at 338.664 -57.536 0)
			(layer "B.Fab")
			(hide yes)
			(effects
				(font
					(size 1 1)
					(thickness 0.15)
				)
				(justify mirror)
			)
		)
		(property "MPN" "CGA2B3X7S2A472K050BB"
			(at 338.664 -57.536 0)
			(layer "B.Fab")
			(hide yes)
			(effects
				(font
					(size 1 1)
					(thickness 0.15)
				)
				(justify mirror)
			)
		)
		(property "Manufacturer" "TDK"
			(at 338.664 -57.536 0)
			(layer "B.Fab")
			(hide yes)
			(effects
				(font
					(size 1 1)
					(thickness 0.15)
				)
				(justify mirror)
			)
		)
		(property "Public" ""
			(at 338.664 -57.536 0)
			(layer "B.Fab")
			(hide yes)
			(effects
				(font
					(size 1 1)
					(thickness 0.15)
				)
				(justify mirror)
			)
		)
		(property "Val" "4n7"
			(at 338.664 -57.536 0)
			(layer "B.Fab")
			(hide yes)
			(effects
				(font
					(size 1 1)
					(thickness 0.15)
				)
				(justify mirror)
			)
		)
		(property "Voltage" "25V"
			(at 338.664 -57.536 0)
			(layer "B.Fab")
			(hide yes)
			(effects
				(font
					(size 1 1)
					(thickness 0.15)
				)
				(justify mirror)
			)
		)
		(sheetname "/FPGA Supply/")
		(sheetfile "fpga-supply.kicad_sch")
		(attr smd)
		(fp_rect
			(start -0.925 0.47)
			(end 0.925 -0.47)
			(stroke
				(width 0.05)
				(type default)
			)
			(fill no)
			(layer "B.CrtYd")
		)
		(fp_line
			(start 0.504 -0.248)
			(end -0.494 -0.248)
			(stroke
				(width 0.15)
				(type solid)
			)
			(layer "B.Fab")
		)
		(fp_line
			(start -0.494 -0.248)
			(end -0.494 0.25)
			(stroke
				(width 0.15)
				(type solid)
			)
			(layer "B.Fab")
		)
		(fp_line
			(start 0.504 0.25)
			(end 0.504 -0.248)
			(stroke
				(width 0.15)
				(type solid)
			)
			(layer "B.Fab")
		)
		(fp_line
			(start -0.494 0.25)
			(end 0.504 0.25)
			(stroke
				(width 0.15)
				(type solid)
			)
			(layer "B.Fab")
		)
		(fp_text user "License: Apache-2.0"
			(at -0.939 -5.799 270)
			(layer "B.Fab")
			(effects
				(font
					(size 0.7 0.7)
					(thickness 0.15)
				)
				(justify left bottom mirror)
			)
		)
		(fp_text user "Author: Antmicro"
			(at -0.939 -3.399 270)
			(layer "B.Fab")
			(effects
				(font
					(size 0.7 0.7)
					(thickness 0.15)
				)
				(justify left bottom mirror)
			)
		)
		(fp_text user "${REFERENCE}"
			(at -0.939 -4.599 270)
			(layer "B.Fab")
			(effects
				(font
					(size 0.7 0.7)
					(thickness 0.15)
				)
				(justify left bottom mirror)
			)
		)
		(pad "1" smd roundrect
			(at -0.48 0 90)
			(size 0.59 0.64)
			(layers "B.Cu" "B.Mask" "B.Paste")
			(roundrect_rratio 0.25)
			(net 417 "GND")
			(pintype "passive")
		)
		(pad "2" smd roundrect
			(at 0.48 0 90)
			(size 0.59 0.64)
			(layers "B.Cu" "B.Mask" "B.Paste")
			(roundrect_rratio 0.25)
			(net 47 "+1V05")
			(pintype "passive")
		)
	)
	(footprint "antmicro-footprints:XSON-8_1x1.95mm_P0.5mm"
		(layer "B.Cu")
		(at 192.3 142.4)
		(property "Reference" "U14"
			(at 1.85 1.25 90)
			(layer "B.SilkS")
			(effects
				(font
					(size 0.7 0.7)
					(thickness 0.15)
				)
				(justify right bottom mirror)
			)
		)
		(property "Value" "NTS0102_XSON"
			(at 0 -2.2 0)
			(layer "B.Fab")
			(hide yes)
			(effects
				(font
					(size 0.7 0.7)
					(thickness 0.15)
				)
				(justify right bottom mirror)
			)
		)
		(property "Datasheet" "http://www.farnell.com/datasheets/1760723.pdf"
			(at 0 0 0)
			(layer "F.Fab")
			(hide yes)
			(effects
				(font
					(size 1.27 1.27)
					(thickness 0.15)
				)
			)
		)
		(property "Description" "Transceiver, 1.65 V to 3.6 V, XSON-8"
			(at 0 0 0)
			(layer "F.Fab")
			(hide yes)
			(effects
				(font
					(size 1.27 1.27)
					(thickness 0.15)
				)
			)
		)
		(property "Author" "Antmicro"
			(at 0 0 0)
			(layer "B.Fab")
			(hide yes)
			(effects
				(font
					(size 1 1)
					(thickness 0.15)
				)
				(justify mirror)
			)
		)
		(property "License" "Apache-2.0"
			(at 0 0 0)
			(layer "B.Fab")
			(hide yes)
			(effects
				(font
					(size 1 1)
					(thickness 0.15)
				)
				(justify mirror)
			)
		)
		(property "MPN" "NTS0102GT"
			(at 0 0 0)
			(layer "B.Fab")
			(hide yes)
			(effects
				(font
					(size 1 1)
					(thickness 0.15)
				)
				(justify mirror)
			)
		)
		(property "Manufacturer" "NXP"
			(at 0 0 0)
			(layer "B.Fab")
			(hide yes)
			(effects
				(font
					(size 1 1)
					(thickness 0.15)
				)
				(justify mirror)
			)
		)
		(sheetname "/FPGA GPIO/")
		(sheetfile "fpga-gpio.kicad_sch")
		(attr smd)
		(fp_line
			(start -0.5 1.1)
			(end 0.5 1.1)
			(stroke
				(width 0.15)
				(type solid)
			)
			(layer "B.SilkS")
		)
		(fp_line
			(start 0.5 -1.1)
			(end -0.5 -1.1)
			(stroke
				(width 0.15)
				(type solid)
			)
			(layer "B.SilkS")
		)
		(fp_circle
			(center -0.75 1.1)
			(end -0.701 1.1)
			(stroke
				(width 0.15)
				(type solid)
			)
			(fill no)
			(layer "B.SilkS")
		)
		(fp_rect
			(start -0.8 1.2)
			(end 0.8 -1.2)
			(stroke
				(width 0.05)
				(type solid)
			)
			(fill no)
			(layer "B.CrtYd")
		)
		(fp_line
			(start -0.5305 -1)
			(end -0.5305 1.001)
			(stroke
				(width 0.15)
				(type solid)
			)
			(layer "B.Fab")
		)
		(fp_line
			(start -0.5305 1.001)
			(end 0.5305 1.001)
			(stroke
				(width 0.15)
				(type solid)
			)
			(layer "B.Fab")
		)
		(fp_line
			(start 0.5305 -1)
			(end -0.5305 -1)
			(stroke
				(width 0.15)
				(type solid)
			)
			(layer "B.Fab")
		)
		(fp_line
			(start 0.5305 1.001)
			(end 0.5305 -1)
			(stroke
				(width 0.15)
				(type solid)
			)
			(layer "B.Fab")
		)
		(fp_text user "Author: Antmicro"
			(at -0.527 -7.105 180)
			(layer "B.Fab")
			(effects
				(font
					(size 0.7 0.7)
					(thickness 0.15)
				)
				(justify left bottom mirror)
			)
		)
		(fp_text user "${REFERENCE}"
			(at -0.527 -5.905 180)
			(layer "B.Fab")
			(effects
				(font
					(size 0.7 0.7)
					(thickness 0.15)
				)
				(justify left bottom mirror)
			)
		)
		(fp_text user "License: Apache-2.0"
			(at -0.527 -8.306 180)
			(layer "B.Fab")
			(effects
				(font
					(size 0.7 0.7)
					(thickness 0.15)
				)
				(justify left bottom mirror)
			)
		)
		(pad "1" smd roundrect
			(at -0.45 0.75 180)
			(size 0.6 0.3)
			(layers "B.Cu" "B.Mask" "B.Paste")
			(roundrect_rratio 0.25)
			(net 283 "/FPGA GPIO/PI3HDX511F.SCL")
			(pinfunction "B_{2}")
			(pintype "bidirectional")
		)
		(pad "2" smd roundrect
			(at -0.45 0.25 180)
			(size 0.6 0.25)
			(layers "B.Cu" "B.Mask" "B.Paste")
			(roundrect_rratio 0.25)
			(net 417 "GND")
			(pinfunction "GND")
			(pintype "power_in")
		)
		(pad "3" smd roundrect
			(at -0.45 -0.25 180)
			(size 0.6 0.25)
			(layers "B.Cu" "B.Mask" "B.Paste")
			(roundrect_rratio 0.25)
			(net 649 "VDD")
			(pinfunction "VCC_{A}")
			(pintype "power_in")
		)
		(pad "4" smd roundrect
			(at -0.45 -0.75 180)
			(size 0.6 0.3)
			(layers "B.Cu" "B.Mask" "B.Paste")
			(roundrect_rratio 0.25)
			(net 353 "/FPGA GPIO/HDMI0_SCL_SRC")
			(pinfunction "A_{2}")
			(pintype "bidirectional")
		)
		(pad "5" smd roundrect
			(at 0.45 -0.75 180)
			(size 0.6 0.3)
			(layers "B.Cu" "B.Mask" "B.Paste")
			(roundrect_rratio 0.25)
			(net 348 "/FPGA GPIO/HDMI0_SDA_SRC")
			(pinfunction "A_{1}")
			(pintype "bidirectional")
		)
		(pad "6" smd roundrect
			(at 0.45 -0.25 180)
			(size 0.6 0.25)
			(layers "B.Cu" "B.Mask" "B.Paste")
			(roundrect_rratio 0.25)
			(net 649 "VDD")
			(pinfunction "OE")
			(pintype "input")
		)
		(pad "7" smd roundrect
			(at 0.45 0.25 180)
			(size 0.6 0.25)
			(layers "B.Cu" "B.Mask" "B.Paste")
			(roundrect_rratio 0.25)
			(net 50 "+3V3")
			(pinfunction "VCC_{B}")
			(pintype "power_in")
		)
		(pad "8" smd roundrect
			(at 0.45 0.75 180)
			(size 0.6 0.3)
			(layers "B.Cu" "B.Mask" "B.Paste")
			(roundrect_rratio 0.25)
			(net 622 "/FPGA GPIO/PI3HDX511F.SDA")
			(pinfunction "B_{1}")
			(pintype "bidirectional")
		)
	)
)
